# T6G (Grand Teton) — schematic netlist excerpt (pin names and nets, part order shuffled) for the footprints in the layout excerpt that follows; sources: Cadence DE-HDL packaged netlist, KiCad conversion of 04192023_DAF0TMB3IC0_F0TG_MB_C_brd_V02_OCP.brd

J20  SCONN288_DDR506112002KQ  IO  pkg DDR288S_1-1VXC  page 96
  VIN_BULK0  = P12V_MEM_CPU0
  RFU0  = NC
  VIN_MGMT  = P3V3_AUX
  HSCL  = I3C_SPD_DDRK_CPU0_SCL
  HSDA  = I3C_SPD_DDRK_CPU0_SDA
  VSS0  = GND
  DQ0_A  = M_K_CPU0_SA_DQ<0>
  VSS1  = GND
  DQ1_A  = M_K_CPU0_SA_DQ<1>
  VSS2  = GND
  DQS0_A_T  = M_K_CPU0_SA_DQS_DP<0>
  DQS0_A_C  = M_K_CPU0_SA_DQS_DN<0>
  VSS3  = GND
  DQ4_A  = M_K_CPU0_SA_DQ<4>
  VSS4  = GND
  DQ5_A  = M_K_CPU0_SA_DQ<5>
  VSS5  = GND
  DQ8_A  = M_K_CPU0_SA_DQ<8>
  VSS6  = GND
  DQ9_A  = M_K_CPU0_SA_DQ<9>
  VSS7  = GND
  DQS1_A_T  = M_K_CPU0_SA_DQS_DP<1>
  DQS1_A_C  = M_K_CPU0_SA_DQS_DN<1>
  VSS8  = GND
  DQ12_A  = M_K_CPU0_SA_DQ<12>
  VSS9  = GND
  DQ13_A  = M_K_CPU0_SA_DQ<13>
  VSS10  = GND
  DQ16_A  = M_K_CPU0_SA_DQ<16>
  VSS11  = GND
  DQ17_A  = M_K_CPU0_SA_DQ<17>
  VSS12  = GND
  DQS2_A_T  = M_K_CPU0_SA_DQS_DP<2>
  DQS2_A_C  = M_K_CPU0_SA_DQS_DN<2>
  VSS13  = GND
  DQ20_A  = M_K_CPU0_SA_DQ<20>
  VSS14  = GND
  DQ21_A  = M_K_CPU0_SA_DQ<21>
  VSS15  = GND
  DQ24_A  = M_K_CPU0_SA_DQ<24>
  VSS16  = GND
  DQ25_A  = M_K_CPU0_SA_DQ<25>
  VSS17  = GND
  DQS3_A_T  = M_K_CPU0_SA_DQS_DP<3>
  DQS3_A_C  = M_K_CPU0_SA_DQS_DN<3>
  VSS18  = GND
  DQ28_A  = M_K_CPU0_SA_DQ<28>
  VSS19  = GND
  DQ29_A  = M_K_CPU0_SA_DQ<29>
  VSS20  = GND
  CB0_A  = M_K_CPU0_SA_CB<0>
  VSS21  = GND
  CB1_A  = M_K_CPU0_SA_CB<1>
  VSS22  = GND
  DQS4_A_T  = M_K_CPU0_SA_DQS_DP<4>
  DQS4_A_C  = M_K_CPU0_SA_DQS_DN<4>
  VSS23  = GND
  CB4_A  = M_K_CPU0_SA_CB<4>
  VSS24  = GND
  CB5_A  = M_K_CPU0_SA_CB<5>
  VSS25  = GND
  ALERT_N  = M_K_CPU0_ALERT_N
  VSS26  = GND
  CS0_A_N  = M_K_CPU0_SA_CS_N<0>
  VSS27  = GND
  CA0_A  = M_K_CPU0_SA_CA<0>
  VSS28  = GND
  CA2_A  = M_K_CPU0_SA_CA<2>
  VSS29  = GND
  CA4_A  = M_K_CPU0_SA_CA<4>
  VSS30  = GND
  CA6_A  = M_K_CPU0_SA_CA<6>
  VSS31  = GND
  PAR_A  = M_K_CPU0_SA_PAR
  VSS32  = GND
  CA0_B  = M_K_CPU0_SB_CA<0>
  VSS33  = GND
  CA2_B  = M_K_CPU0_SB_CA<2>
  VSS34  = GND
  CA4_B  = M_K_CPU0_SB_CA<4>
  VSS35  = GND
  CA6_B  = M_K_CPU0_SB_CA<6>
  VSS36  = GND
  CS0_B_N  = M_K_CPU0_SB_CS_N<0>
  VSS37  = GND
  \lbd||rsp_a_n\  = M_K_CPU0_SA_RSP<0>
  \lbs||rsp_b_n\  = M_K_CPU0_SB_RSP<0>
  VSS38  = GND
  CB4_B  = M_K_CPU0_SB_CB<4>
  VSS39  = GND
  CB5_B  = M_K_CPU0_SB_CB<5>
  VSS40  = GND
  \dqs9_b_t||tdqs9_b_t||dbi4_b_n\  = M_K_CPU0_SB_DQS_DP<9>
  \dqs9_b_c||tdqs9_b_c\  = M_K_CPU0_SB_DQS_DN<9>
  VSS41  = GND
  CB0_B  = M_K_CPU0_SB_CB<0>
  VSS42  = GND
  CB1_B  = M_K_CPU0_SB_CB<1>
  VSS43  = GND
  DQ0_B  = M_K_CPU0_SB_DQ<0>
  VSS44  = GND
  DQ1_B  = M_K_CPU0_SB_DQ<1>
  VSS45  = GND
  DQS0_B_T  = M_K_CPU0_SB_DQS_DP<0>
  DQS0_B_C  = M_K_CPU0_SB_DQS_DN<0>
  VSS46  = GND
  DQ4_B  = M_K_CPU0_SB_DQ<4>
  VSS47  = GND
  DQ5_B  = M_K_CPU0_SB_DQ<5>
  VSS48  = GND
  DQ8_B  = M_K_CPU0_SB_DQ<8>
  VSS49  = GND
  DQ9_B  = M_K_CPU0_SB_DQ<9>
  VSS50  = GND
  DQS1_B_T  = M_K_CPU0_SB_DQS_DP<1>
  DQS1_B_C  = M_K_CPU0_SB_DQS_DN<1>
  VSS51  = GND
  DQ12_B  = M_K_CPU0_SB_DQ<12>
  VSS52  = GND
  DQ13_B  = M_K_CPU0_SB_DQ<13>
  VSS53  = GND
  DQ16_B  = M_K_CPU0_SB_DQ<16>
  VSS54  = GND
  DQ17_B  = M_K_CPU0_SB_DQ<17>
  VSS55  = GND
  DQS2_B_T  = M_K_CPU0_SB_DQS_DP<2>
  DQS2_B_C  = M_K_CPU0_SB_DQS_DN<2>
  VSS56  = GND
  DQ20_B  = M_K_CPU0_SB_DQ<20>
  VSS57  = GND
  DQ21_B  = M_K_CPU0_SB_DQ<21>
  VSS58  = GND
  DQ24_B  = M_K_CPU0_SB_DQ<24>
  VSS59  = GND
  DQ25_B  = M_K_CPU0_SB_DQ<25>
  VSS60  = GND
  DQS3_B_T  = M_K_CPU0_SB_DQS_DP<3>
  DQS3_B_C  = M_K_CPU0_SB_DQS_DN<3>
  VSS61  = GND
  DQ28_B  = M_K_CPU0_SB_DQ<28>
  VSS62  = GND
  DQ29_B  = M_K_CPU0_SB_DQ<29>
  VSS63  = GND
  RFU1  = NC
  VIN_BULK1  = P12V_MEM_CPU0
  VIN_BULK2  = P12V_MEM_CPU0
  \pwr_good||fail_n\  = PWRGD_CHK_CPU0_DIMM
  HAS  = PD_CHK_CPU0_DIMM_SAA
  RFU2  = NC
  RFU3  = NC
  VSS64  = GND
  DQ2_A  = M_K_CPU0_SA_DQ<2>
  VSS65  = GND
  DQ3_A  = M_K_CPU0_SA_DQ<3>
  VSS66  = GND
  \dqs5_a_c||tdqs5_a_c||dqs5_a_t||tdqs5_a_t\  = M_K_CPU0_SA_DQS_DN<5>
  \dqs5_a_t||tdqs5_a_t\  = M_K_CPU0_SA_DQS_DP<5>
  VSS67  = GND
  DQ6_A  = M_K_CPU0_SA_DQ<6>
  VSS68  = GND
  DQ7_A  = M_K_CPU0_SA_DQ<7>
  VSS69  = GND
  DQ10_A  = M_K_CPU0_SA_DQ<10>
  VSS70  = GND
  DQ11_A  = M_K_CPU0_SA_DQ<11>
  VSS71  = GND
  \dqs6_a_c||tdqs6_a_c||dqs6_a_t||tdqs6_a_t\  = M_K_CPU0_SA_DQS_DN<6>
  \dqs6_a_t||tdqs6_a_t\  = M_K_CPU0_SA_DQS_DP<6>
  VSS72  = GND
  DQ14_A  = M_K_CPU0_SA_DQ<14>
  VSS73  = GND
  DQ15_A  = M_K_CPU0_SA_DQ<15>
  VSS74  = GND
  DQ18_A  = M_K_CPU0_SA_DQ<18>
  VSS75  = GND
  DQ19_A  = M_K_CPU0_SA_DQ<19>
  VSS76  = GND
  \dqs7_a_c||tdqs7_a_c\  = M_K_CPU0_SA_DQS_DN<7>
  \dqs7_a_t||tdqs7_a_t\  = M_K_CPU0_SA_DQS_DP<7>
  VSS77  = GND
  DQ22_A  = M_K_CPU0_SA_DQ<22>
  VSS78  = GND
  DQ23_A  = M_K_CPU0_SA_DQ<23>
  VSS79  = GND
  DQ26_A  = M_K_CPU0_SA_DQ<26>
  VSS80  = GND
  DQ27_A  = M_K_CPU0_SA_DQ<27>
  VSS81  = GND
  \dqs8_a_c||tdqs8_a_c\  = M_K_CPU0_SA_DQS_DN<8>
  \dqs8_a_t||tdqs8_a_t\  = M_K_CPU0_SA_DQS_DP<8>
  VSS82  = GND
  DQ30_A  = M_K_CPU0_SA_DQ<30>
  VSS83  = GND
  DQ31_A  = M_K_CPU0_SA_DQ<31>
  VSS84  = GND
  CB2_A  = M_K_CPU0_SA_CB<2>
  VSS85  = GND
  CB3_A  = M_K_CPU0_SA_CB<3>
  VSS86  = GND
  \dqs9_a_c||tdqs9_a_c\  = M_K_CPU0_SA_DQS_DN<9>
  \dqs9_a_t||tdqs9_a_t\  = M_K_CPU0_SA_DQS_DP<9>
  VSS87  = GND
  CB6_A  = M_K_CPU0_SA_CB<6>
  VSS88  = GND
  CB7_A  = M_K_CPU0_SA_CB<7>
  VSS89  = GND
  RESET_N  = M_K_CPU0_RESET_N
  VSS90  = GND
  CS1_A_N  = M_K_CPU0_SA_CS_N<1>
  VSS91  = GND
  CA1_A  = M_K_CPU0_SA_CA<1>
  VSS92  = GND
  CA3_A  = M_K_CPU0_SA_CA<3>
  VSS93  = GND
  CA5_A  = M_K_CPU0_SA_CA<5>
  VSS94  = GND
  CK_T  = M_K_CPU0_CLK_DP<0>
  CK_C  = M_K_CPU0_CLK_DN<0>
  VSS95  = GND
  RFU4  = NC
  CA1_B  = M_K_CPU0_SB_CA<1>
  VSS96  = GND
  CA3_B  = M_K_CPU0_SB_CA<3>
  VSS97  = GND
  CA5_B  = M_K_CPU0_SB_CA<5>
  VSS98  = GND
  PAR_B  = M_K_CPU0_SB_PAR
  VSS99  = GND
  CS1_B_N  = M_K_CPU0_SB_CS_N<1>
  VSS100  = GND
  RFU5  = NC
  RFU6  = NC
  VSS101  = GND
  CB6_B  = M_K_CPU0_SB_CB<6>
  VSS102  = GND
  CB7_B  = M_K_CPU0_SB_CB<7>
  VSS103  = GND
  DQS4_B_C  = M_K_CPU0_SB_DQS_DN<4>
  DQS4_B_T  = M_K_CPU0_SB_DQS_DP<4>
  VSS104  = GND
  CB2_B  = M_K_CPU0_SB_CB<2>
  VSS105  = GND
  CB3_B  = M_K_CPU0_SB_CB<3>
  VSS106  = GND
  DQ2_B  = M_K_CPU0_SB_DQ<2>
  VSS107  = GND
  DQ3_B  = M_K_CPU0_SB_DQ<3>
  VSS108  = GND
  \dqs5_b_c||tdqs5_b_c\  = M_K_CPU0_SB_DQS_DN<5>
  \dqs5_b_t||tdqs5_b_t\  = M_K_CPU0_SB_DQS_DP<5>
  VSS109  = GND
  DQ6_B  = M_K_CPU0_SB_DQ<6>
  VSS110  = GND
  DQ7_B  = M_K_CPU0_SB_DQ<7>
  VSS111  = GND
  DQ10_B  = M_K_CPU0_SB_DQ<10>
  VSS112  = GND
  DQ11_B  = M_K_CPU0_SB_DQ<11>
  VSS113  = GND
  \dqs6_b_c||tdqs6_b_c\  = M_K_CPU0_SB_DQS_DN<6>
  \dqs6_b_t||tdqs6_b_t\  = M_K_CPU0_SB_DQS_DP<6>
  VSS114  = GND
  DQ14_B  = M_K_CPU0_SB_DQ<14>
  VSS115  = GND
  DQ15_B  = M_K_CPU0_SB_DQ<15>
  VSS116  = GND
  DQ18_B  = M_K_CPU0_SB_DQ<18>
  VSS117  = GND
  DQ19_B  = M_K_CPU0_SB_DQ<19>
  VSS118  = GND
  \dqs7_b_c||tdqs7_b_c\  = M_K_CPU0_SB_DQS_DN<7>
  \dqs7_b_t||tdqs7_b_t\  = M_K_CPU0_SB_DQS_DP<7>
  VSS119  = GND
  DQ22_B  = M_K_CPU0_SB_DQ<22>
  VSS120  = GND
  DQ23_B  = M_K_CPU0_SB_DQ<23>
  VSS121  = GND
  DQ26_B  = M_K_CPU0_SB_DQ<26>
  VSS122  = GND
  DQ27_B  = M_K_CPU0_SB_DQ<27>
  VSS123  = GND
  \dqs8_b_c||tdqs8_b_c\  = M_K_CPU0_SB_DQS_DN<8>
  \dqs8_b_t||tdqs8_b_t\  = M_K_CPU0_SB_DQS_DP<8>
  VSS124  = GND
  DQ30_B  = M_K_CPU0_SB_DQ<30>
  VSS125  = GND
  DQ31_B  = M_K_CPU0_SB_DQ<31>
  VSS126  = GND
  G1  = GND
  G2  = GND
  G3  = GND

(kicad_pcb
	(version 20260206)
	(generator "pcbnew")
	(generator_version "10.0")
	(general
		(thickness 1.6)
		(legacy_teardrops no)
	)
	(paper "A4")
	(title_block
		(title "04192023_DAF0TMB3IC0_F0TG_MB_C_brd_V02_OCP.brd")
		(comment 1 "Grand Teton / footprint 2165 of 8354 (J20), pads 1-46 of 291")
	)
	(layers
		(0 "F.Cu" signal "TOP")
		(4 "In1.Cu" signal "GND")
		(6 "In2.Cu" signal "IN1")
		(8 "In3.Cu" signal "GND1")
		(10 "In4.Cu" signal "IN2")
		(12 "In5.Cu" signal "GND2")
		(14 "In6.Cu" signal "IN3")
		(16 "In7.Cu" signal "GND3")
		(18 "In8.Cu" signal "VCC")
		(20 "In9.Cu" signal "VCC1")
		(22 "In10.Cu" signal "GND4")
		(24 "In11.Cu" signal "IN4")
		(26 "In12.Cu" signal "GND5")
		(28 "In13.Cu" signal "IN5")
		(30 "In14.Cu" signal "GND6")
		(32 "In15.Cu" signal "IN6")
		(34 "In16.Cu" signal "GND7")
		(2 "B.Cu" signal "BOTTOM")
		(9 "F.Adhes" user "F.Adhesive")
		(11 "B.Adhes" user "B.Adhesive")
		(13 "F.Paste" user "Package Geometry/Pastemask Top")
		(15 "B.Paste" user "Package Geometry/Pastemask Bottom")
		(5 "F.SilkS" user "Ref Des/Silkscreen Top")
		(7 "B.SilkS" user "Ref Des/Silkscreen Bottom")
		(1 "F.Mask" user "Board Geometry/Soldermask Top")
		(3 "B.Mask" user "Board Geometry/Soldermask Bottom")
		(17 "Dwgs.User" user "User.Drawings")
		(19 "Cmts.User" user "User.Comments")
		(21 "Eco1.User" user "User.Eco1")
		(23 "Eco2.User" user "User.Eco2")
		(25 "Edge.Cuts" user "Board Geometry/Outline")
		(27 "Margin" user)
		(31 "F.CrtYd" user "Package Geometry/Place Bound Top")
		(29 "B.CrtYd" user "Package Geometry/Place Bound Bottom")
		(35 "F.Fab" user "Ref Des/Assembly Top")
		(33 "B.Fab" user "Ref Des/Assembly Bottom")
	)
	(footprint ""
		(layer "F.Cu")
		(at 444.594234 -255.560068 180)
		(property "Reference" "J20"
			(at 1.631188 -81.796128 0)
			(unlocked yes)
			(layer "F.SilkS")
			(effects
				(font
					(size 0.7874 0.5842)
					(thickness 0.1524)
				)
			)
		)
		(property "Value" ""
			(at 0 0 180)
			(layer "F.Fab")
			(effects
				(font
					(size 1.27 1.27)
				)
			)
		)
		(duplicate_pad_numbers_are_jumpers no)
		(pad "1" smd rect
			(at -2.050034 -63.324994 90)
			(size 0.519938 1.4986)
			(layers "F.Cu" "F.Mask" "F.Paste")
			(net "P12V_MEM_CPU0")
		)
		(pad "2" smd rect
			(at -2.050034 -62.47511 90)
			(size 0.519938 1.4986)
			(layers "F.Cu" "F.Mask" "F.Paste")
			(net "Net_2389")
		)
		(pad "3" smd rect
			(at -2.050034 -61.624972 90)
			(size 0.519938 1.4986)
			(layers "F.Cu" "F.Mask" "F.Paste")
			(net "P3V3_AUX")
		)
		(pad "4" smd rect
			(at -2.050034 -60.775088 90)
			(size 0.519938 1.4986)
			(layers "F.Cu" "F.Mask" "F.Paste")
			(net "I3C_SPD_DDRK_CPU0_SCL")
		)
		(pad "5" smd rect
			(at -2.050034 -59.92495 90)
			(size 0.519938 1.4986)
			(layers "F.Cu" "F.Mask" "F.Paste")
			(net "I3C_SPD_DDRK_CPU0_SDA")
		)
		(pad "6" smd rect
			(at -2.050034 -59.075066 90)
			(size 0.519938 1.4986)
			(layers "F.Cu" "F.Mask" "F.Paste")
			(net "GND")
		)
		(pad "7" smd rect
			(at -2.050034 -58.224928 90)
			(size 0.519938 1.4986)
			(layers "F.Cu" "F.Mask" "F.Paste")
			(net "M_K_CPU0_SA_DQ<0>")
		)
		(pad "8" smd rect
			(at -2.050034 -57.375044 90)
			(size 0.519938 1.4986)
			(layers "F.Cu" "F.Mask" "F.Paste")
			(net "GND")
		)
		(pad "9" smd rect
			(at -2.050034 -56.524906 90)
			(size 0.519938 1.4986)
			(layers "F.Cu" "F.Mask" "F.Paste")
			(net "M_K_CPU0_SA_DQ<1>")
		)
		(pad "10" smd rect
			(at -2.050034 -55.675022 90)
			(size 0.519938 1.4986)
			(layers "F.Cu" "F.Mask" "F.Paste")
			(net "GND")
		)
		(pad "11" smd rect
			(at -2.050034 -54.824884 90)
			(size 0.519938 1.4986)
			(layers "F.Cu" "F.Mask" "F.Paste")
			(net "M_K_CPU0_SA_DQS_DP<0>")
		)
		(pad "12" smd rect
			(at -2.050034 -53.975 90)
			(size 0.519938 1.4986)
			(layers "F.Cu" "F.Mask" "F.Paste")
			(net "M_K_CPU0_SA_DQS_DN<0>")
		)
		(pad "13" smd rect
			(at -2.050034 -53.125116 90)
			(size 0.519938 1.4986)
			(layers "F.Cu" "F.Mask" "F.Paste")
			(net "GND")
		)
		(pad "14" smd rect
			(at -2.050034 -52.274978 90)
			(size 0.519938 1.4986)
			(layers "F.Cu" "F.Mask" "F.Paste")
			(net "M_K_CPU0_SA_DQ<4>")
		)
		(pad "15" smd rect
			(at -2.050034 -51.425094 90)
			(size 0.519938 1.4986)
			(layers "F.Cu" "F.Mask" "F.Paste")
			(net "GND")
		)
		(pad "16" smd rect
			(at -2.050034 -50.574956 90)
			(size 0.519938 1.4986)
			(layers "F.Cu" "F.Mask" "F.Paste")
			(net "M_K_CPU0_SA_DQ<5>")
		)
		(pad "17" smd rect
			(at -2.050034 -49.725072 90)
			(size 0.519938 1.4986)
			(layers "F.Cu" "F.Mask" "F.Paste")
			(net "GND")
		)
		(pad "18" smd rect
			(at -2.050034 -48.874934 90)
			(size 0.519938 1.4986)
			(layers "F.Cu" "F.Mask" "F.Paste")
			(net "M_K_CPU0_SA_DQ<8>")
		)
		(pad "19" smd rect
			(at -2.050034 -48.02505 90)
			(size 0.519938 1.4986)
			(layers "F.Cu" "F.Mask" "F.Paste")
			(net "GND")
		)
		(pad "20" smd rect
			(at -2.050034 -47.174912 90)
			(size 0.519938 1.4986)
			(layers "F.Cu" "F.Mask" "F.Paste")
			(net "M_K_CPU0_SA_DQ<9>")
		)
		(pad "21" smd rect
			(at -2.050034 -46.325028 90)
			(size 0.519938 1.4986)
			(layers "F.Cu" "F.Mask" "F.Paste")
			(net "GND")
		)
		(pad "22" smd rect
			(at -2.050034 -45.47489 90)
			(size 0.519938 1.4986)
			(layers "F.Cu" "F.Mask" "F.Paste")
			(net "M_K_CPU0_SA_DQS_DP<1>")
		)
		(pad "23" smd rect
			(at -2.050034 -44.625006 90)
			(size 0.519938 1.4986)
			(layers "F.Cu" "F.Mask" "F.Paste")
			(net "M_K_CPU0_SA_DQS_DN<1>")
		)
		(pad "24" smd rect
			(at -2.050034 -43.775122 90)
			(size 0.519938 1.4986)
			(layers "F.Cu" "F.Mask" "F.Paste")
			(net "GND")
		)
		(pad "25" smd rect
			(at -2.050034 -42.924984 90)
			(size 0.519938 1.4986)
			(layers "F.Cu" "F.Mask" "F.Paste")
			(net "M_K_CPU0_SA_DQ<12>")
		)
		(pad "26" smd rect
			(at -2.050034 -42.0751 90)
			(size 0.519938 1.4986)
			(layers "F.Cu" "F.Mask" "F.Paste")
			(net "GND")
		)
		(pad "27" smd rect
			(at -2.050034 -41.224962 90)
			(size 0.519938 1.4986)
			(layers "F.Cu" "F.Mask" "F.Paste")
			(net "M_K_CPU0_SA_DQ<13>")
		)
		(pad "28" smd rect
			(at -2.050034 -40.375078 90)
			(size 0.519938 1.4986)
			(layers "F.Cu" "F.Mask" "F.Paste")
			(net "GND")
		)
		(pad "29" smd rect
			(at -2.050034 -39.52494 90)
			(size 0.519938 1.4986)
			(layers "F.Cu" "F.Mask" "F.Paste")
			(net "M_K_CPU0_SA_DQ<16>")
		)
		(pad "30" smd rect
			(at -2.050034 -38.675056 90)
			(size 0.519938 1.4986)
			(layers "F.Cu" "F.Mask" "F.Paste")
			(net "GND")
		)
		(pad "31" smd rect
			(at -2.050034 -37.824918 90)
			(size 0.519938 1.4986)
			(layers "F.Cu" "F.Mask" "F.Paste")
			(net "M_K_CPU0_SA_DQ<17>")
		)
		(pad "32" smd rect
			(at -2.050034 -36.975034 90)
			(size 0.519938 1.4986)
			(layers "F.Cu" "F.Mask" "F.Paste")
			(net "GND")
		)
		(pad "33" smd rect
			(at -2.050034 -36.124896 90)
			(size 0.519938 1.4986)
			(layers "F.Cu" "F.Mask" "F.Paste")
			(net "M_K_CPU0_SA_DQS_DP<2>")
		)
		(pad "34" smd rect
			(at -2.050034 -35.275012 90)
			(size 0.519938 1.4986)
			(layers "F.Cu" "F.Mask" "F.Paste")
			(net "M_K_CPU0_SA_DQS_DN<2>")
		)
		(pad "35" smd rect
			(at -2.050034 -34.425128 90)
			(size 0.519938 1.4986)
			(layers "F.Cu" "F.Mask" "F.Paste")
			(net "GND")
		)
		(pad "36" smd rect
			(at -2.050034 -33.57499 90)
			(size 0.519938 1.4986)
			(layers "F.Cu" "F.Mask" "F.Paste")
			(net "M_K_CPU0_SA_DQ<20>")
		)
		(pad "37" smd rect
			(at -2.050034 -32.725106 90)
			(size 0.519938 1.4986)
			(layers "F.Cu" "F.Mask" "F.Paste")
			(net "GND")
		)
		(pad "38" smd rect
			(at -2.050034 -31.874968 90)
			(size 0.519938 1.4986)
			(layers "F.Cu" "F.Mask" "F.Paste")
			(net "M_K_CPU0_SA_DQ<21>")
		)
		(pad "39" smd rect
			(at -2.050034 -31.025084 90)
			(size 0.519938 1.4986)
			(layers "F.Cu" "F.Mask" "F.Paste")
			(net "GND")
		)
		(pad "40" smd rect
			(at -2.050034 -30.174946 90)
			(size 0.519938 1.4986)
			(layers "F.Cu" "F.Mask" "F.Paste")
			(net "M_K_CPU0_SA_DQ<24>")
		)
		(pad "41" smd rect
			(at -2.050034 -29.325062 90)
			(size 0.519938 1.4986)
			(layers "F.Cu" "F.Mask" "F.Paste")
			(net "GND")
		)
		(pad "42" smd rect
			(at -2.050034 -28.474924 90)
			(size 0.519938 1.4986)
			(layers "F.Cu" "F.Mask" "F.Paste")
			(net "M_K_CPU0_SA_DQ<25>")
		)
		(pad "43" smd rect
			(at -2.050034 -27.62504 90)
			(size 0.519938 1.4986)
			(layers "F.Cu" "F.Mask" "F.Paste")
			(net "GND")
		)
		(pad "44" smd rect
			(at -2.050034 -26.774902 90)
			(size 0.519938 1.4986)
			(layers "F.Cu" "F.Mask" "F.Paste")
			(net "M_K_CPU0_SA_DQS_DP<3>")
		)
		(pad "45" smd rect
			(at -2.050034 -25.925018 90)
			(size 0.519938 1.4986)
			(layers "F.Cu" "F.Mask" "F.Paste")
			(net "M_K_CPU0_SA_DQS_DN<3>")
		)
		(pad "46" smd rect
			(at -2.050034 -25.07488 90)
			(size 0.519938 1.4986)
			(layers "F.Cu" "F.Mask" "F.Paste")
			(net "GND")
		)
	)
)
